# T6G (Grand Teton) — schematic netlist excerpt (pin names and nets, part order shuffled) for the footprints in the layout excerpt that follows; sources: Cadence DE-HDL packaged netlist, KiCad conversion of 04192023_DAF0TMB3IC0_F0TG_MB_C_brd_V02_OCP.brd

J80  PICOPROBE_BXA  DELTA-L 4.0 EMPTY  pkg TRIANG_LAUNCH_3PXB  page 229
  \1_p\  = DELTA_L_85_10INCH_IN4_DP
  \2_n\  = DELTA_L_85_10INCH_IN4_DN
  \3_g\  = DELTA_L_GND_1

(kicad_pcb
	(version 20260206)
	(generator "pcbnew")
	(generator_version "10.0")
	(general
		(thickness 1.6)
		(legacy_teardrops no)
	)
	(paper "A4")
	(title_block
		(title "04192023_DAF0TMB3IC0_F0TG_MB_C_brd_V02_OCP.brd")
		(comment 1 "Grand Teton / footprints 7002-7002 of 8354")
	)
	(layers
		(0 "F.Cu" signal "TOP")
		(4 "In1.Cu" signal "GND")
		(6 "In2.Cu" signal "IN1")
		(8 "In3.Cu" signal "GND1")
		(10 "In4.Cu" signal "IN2")
		(12 "In5.Cu" signal "GND2")
		(14 "In6.Cu" signal "IN3")
		(16 "In7.Cu" signal "GND3")
		(18 "In8.Cu" signal "VCC")
		(20 "In9.Cu" signal "VCC1")
		(22 "In10.Cu" signal "GND4")
		(24 "In11.Cu" signal "IN4")
		(26 "In12.Cu" signal "GND5")
		(28 "In13.Cu" signal "IN5")
		(30 "In14.Cu" signal "GND6")
		(32 "In15.Cu" signal "IN6")
		(34 "In16.Cu" signal "GND7")
		(2 "B.Cu" signal "BOTTOM")
		(9 "F.Adhes" user "F.Adhesive")
		(11 "B.Adhes" user "B.Adhesive")
		(13 "F.Paste" user "Package Geometry/Pastemask Top")
		(15 "B.Paste" user "Package Geometry/Pastemask Bottom")
		(5 "F.SilkS" user "Ref Des/Silkscreen Top")
		(7 "B.SilkS" user "Ref Des/Silkscreen Bottom")
		(1 "F.Mask" user "Board Geometry/Soldermask Top")
		(3 "B.Mask" user "Board Geometry/Soldermask Bottom")
		(17 "Dwgs.User" user "User.Drawings")
		(19 "Cmts.User" user "User.Comments")
		(21 "Eco1.User" user "User.Eco1")
		(23 "Eco2.User" user "User.Eco2")
		(25 "Edge.Cuts" user "Board Geometry/Outline")
		(27 "Margin" user)
		(31 "F.CrtYd" user "Package Geometry/Place Bound Top")
		(29 "B.CrtYd" user "Package Geometry/Place Bound Bottom")
		(35 "F.Fab" user "Ref Des/Assembly Top")
		(33 "B.Fab" user "Ref Des/Assembly Bottom")
	)
	(footprint ""
		(layer "B.Cu")
		(at 212.471508 -2.537206 180)
		(property "Reference" "J80"
			(at 4.56946 -1.086358 270)
			(unlocked yes)
			(layer "B.SilkS")
			(effects
				(font
					(size 0.7874 0.5842)
					(thickness 0.1524)
				)
				(justify left mirror)
			)
		)
		(property "Value" ""
			(at 0 0 0)
			(layer "B.Fab")
			(effects
				(font
					(size 1.27 1.27)
				)
				(justify mirror)
			)
		)
		(duplicate_pad_numbers_are_jumpers no)
		(fp_line
			(start 1.2192 2.06756)
			(end 1.2192 -2.06756)
			(stroke
				(width 0.1524)
				(type default)
			)
			(layer "B.SilkS")
		)
		(fp_line
			(start 1.2192 -2.06756)
			(end -1.2192 -2.06756)
			(stroke
				(width 0.1524)
				(type default)
			)
			(layer "B.SilkS")
		)
		(fp_line
			(start -1.2192 2.06756)
			(end 1.2192 2.06756)
			(stroke
				(width 0.1524)
				(type default)
			)
			(layer "B.SilkS")
		)
		(fp_line
			(start -1.2192 -2.06756)
			(end -1.2192 2.06756)
			(stroke
				(width 0.1524)
				(type default)
			)
			(layer "B.SilkS")
		)
		(pad "" np_thru_hole circle
			(at -3.4671 -1.27 90)
			(size 1.0414 1.0414)
			(drill 1.0414)
			(layers "*.Cu" "*.Mask")
			(clearance 0.381)
			(thermal_gap 0.381)
		)
		(pad "" np_thru_hole circle
			(at -3.4671 1.27 90)
			(size 1.0414 1.0414)
			(drill 1.0414)
			(layers "*.Cu" "*.Mask")
			(clearance 0.381)
			(thermal_gap 0.381)
		)
		(pad "" np_thru_hole circle
			(at 2.8829 -1.27 90)
			(size 1.0414 1.0414)
			(drill 1.0414)
			(layers "*.Cu" "*.Mask")
			(clearance 0.381)
			(thermal_gap 0.381)
		)
		(pad "" np_thru_hole circle
			(at 2.8829 1.27 90)
			(size 1.0414 1.0414)
			(drill 1.0414)
			(layers "*.Cu" "*.Mask")
			(clearance 0.381)
			(thermal_gap 0.381)
		)
		(pad "1" smd rect
			(at -0.8255 -0.249936 90)
			(size 0.3048 0.508)
			(layers "B.Cu" "B.Mask" "B.Paste")
			(net "DELTA_L_85_10INCH_IN4_DP")
		)
		(pad "2" smd rect
			(at -0.8255 0.249936 90)
			(size 0.3048 0.508)
			(layers "B.Cu" "B.Mask" "B.Paste")
			(net "DELTA_L_85_10INCH_IN4_DN")
		)
		(pad "3" smd circle
			(at 0 0)
			(size 0 0)
			(layers "B.Cu" "B.Mask" "B.Paste")
			(net "DELTA_L_GND_1")
		)
		(zone
			(layers "F.Cu" "B.Cu" "In1.Cu" "In2.Cu" "In3.Cu" "In4.Cu" "In5.Cu" "In6.Cu"
				"In7.Cu" "In8.Cu" "In9.Cu" "In10.Cu" "In11.Cu" "In12.Cu" "In13.Cu" "In14.Cu"
				"In15.Cu" "In16.Cu"
			)
			(hatch none 0.5)
			(connect_pads
				(clearance 0)
			)
			(min_thickness 0.25)
			(keepout
				(tracks not_allowed)
				(vias allowed)
				(pads allowed)
				(copperpour not_allowed)
				(footprints allowed)
			)
			(placement
				(enabled no)
				(sheetname "")
			)
			(fill
				(thermal_gap 0.5)
				(thermal_bridge_width 0.5)
				(island_removal_mode 0)
			)
			(polygon
				(pts
					(arc
						(start 210.515708 -3.807206)
						(mid 208.661508 -3.807206)
						(end 210.515708 -3.807206)
					)
				)
			)
		)
		(zone
			(layers "F.Cu" "B.Cu" "In1.Cu" "In2.Cu" "In3.Cu" "In4.Cu" "In5.Cu" "In6.Cu"
				"In7.Cu" "In8.Cu" "In9.Cu" "In10.Cu" "In11.Cu" "In12.Cu" "In13.Cu" "In14.Cu"
				"In15.Cu" "In16.Cu"
			)
			(hatch none 0.5)
			(connect_pads
				(clearance 0)
			)
			(min_thickness 0.25)
			(keepout
				(tracks not_allowed)
				(vias allowed)
				(pads allowed)
				(copperpour not_allowed)
				(footprints allowed)
			)
			(placement
				(enabled no)
				(sheetname "")
			)
			(fill
				(thermal_gap 0.5)
				(thermal_bridge_width 0.5)
				(island_removal_mode 0)
			)
			(polygon
				(pts
					(arc
						(start 210.515708 -1.267206)
						(mid 208.661508 -1.267206)
						(end 210.515708 -1.267206)
					)
				)
			)
		)
		(zone
			(layers "F.Cu" "B.Cu" "In1.Cu" "In2.Cu" "In3.Cu" "In4.Cu" "In5.Cu" "In6.Cu"
				"In7.Cu" "In8.Cu" "In9.Cu" "In10.Cu" "In11.Cu" "In12.Cu" "In13.Cu" "In14.Cu"
				"In15.Cu" "In16.Cu"
			)
			(hatch none 0.5)
			(connect_pads
				(clearance 0)
			)
			(min_thickness 0.25)
			(keepout
				(tracks not_allowed)
				(vias allowed)
				(pads allowed)
				(copperpour not_allowed)
				(footprints allowed)
			)
			(placement
				(enabled no)
				(sheetname "")
			)
			(fill
				(thermal_gap 0.5)
				(thermal_bridge_width 0.5)
				(island_removal_mode 0)
			)
			(polygon
				(pts
					(arc
						(start 216.865708 -3.807206)
						(mid 215.011508 -3.807206)
						(end 216.865708 -3.807206)
					)
				)
			)
		)
		(zone
			(layers "F.Cu" "B.Cu" "In1.Cu" "In2.Cu" "In3.Cu" "In4.Cu" "In5.Cu" "In6.Cu"
				"In7.Cu" "In8.Cu" "In9.Cu" "In10.Cu" "In11.Cu" "In12.Cu" "In13.Cu" "In14.Cu"
				"In15.Cu" "In16.Cu"
			)
			(hatch none 0.5)
			(connect_pads
				(clearance 0)
			)
			(min_thickness 0.25)
			(keepout
				(tracks not_allowed)
				(vias allowed)
				(pads allowed)
				(copperpour not_allowed)
				(footprints allowed)
			)
			(placement
				(enabled no)
				(sheetname "")
			)
			(fill
				(thermal_gap 0.5)
				(thermal_bridge_width 0.5)
				(island_removal_mode 0)
			)
			(polygon
				(pts
					(arc
						(start 216.865708 -1.267206)
						(mid 215.011508 -1.267206)
						(end 216.865708 -1.267206)
					)
				)
			)
		)
		(zone
			(layer "B.Cu")
			(hatch none 0.5)
			(connect_pads
				(clearance 0)
			)
			(min_thickness 0.25)
			(keepout
				(tracks not_allowed)
				(vias allowed)
				(pads allowed)
				(copperpour not_allowed)
				(footprints allowed)
			)
			(placement
				(enabled no)
				(sheetname "")
			)
			(fill
				(thermal_gap 0.5)
				(thermal_bridge_width 0.5)
				(island_removal_mode 0)
			)
			(polygon
				(pts
					(xy 213.589108 -1.988566) (xy 213.589108 -2.08407) (xy 212.992208 -2.08407) (xy 212.992208 -2.49047)
					(xy 213.589108 -2.49047) (xy 213.589108 -2.583942) (xy 212.992208 -2.583942) (xy 212.992208 -2.990342)
					(xy 213.589108 -2.990342) (xy 213.589108 -3.085846) (xy 212.890608 -3.085846) (xy 212.890608 -1.988566)
				)
			)
		)
	)
)
